(kicad_pcb
	(version 20260206)
	(generator "pcbnew")
	(generator_version "10.0")
	(general
		(thickness 1.6)
		(legacy_teardrops no)
	)
	(paper "A4")
	(title_block
		(title "netronome-mezz — pcbd0082-001_rev01_jul9_a.brd")
		(comment 1 "Open CloudServer (Microsoft) / footprints 104-110 of 714")
	)
	(layers
		(0 "F.Cu" signal "TOP")
		(4 "In1.Cu" signal "02_GND")
		(6 "In2.Cu" signal "03_SIG")
		(8 "In3.Cu" signal "04_SIG")
		(10 "In4.Cu" signal "05_GND")
		(12 "In5.Cu" signal "06_PWR1")
		(14 "In6.Cu" signal "07_SIG")
		(16 "In7.Cu" signal "08_SIG")
		(18 "In8.Cu" signal "09_GND")
		(2 "B.Cu" signal "BOTTOM")
		(9 "F.Adhes" user "F.Adhesive")
		(11 "B.Adhes" user "B.Adhesive")
		(13 "F.Paste" user "Package Geometry/Pastemask Top")
		(15 "B.Paste" user "Package Geometry/Pastemask Bottom")
		(5 "F.SilkS" user "Ref Des/Silkscreen Top")
		(7 "B.SilkS" user "Ref Des/Silkscreen Bottom")
		(1 "F.Mask" user "Board Geometry/Soldermask Top")
		(3 "B.Mask" user "Board Geometry/Soldermask Bottom")
		(17 "Dwgs.User" user "User.Drawings")
		(19 "Cmts.User" user "User.Comments")
		(21 "Eco1.User" user "User.Eco1")
		(23 "Eco2.User" user "User.Eco2")
		(25 "Edge.Cuts" user "Board Geometry/Outline")
		(27 "Margin" user)
		(31 "F.CrtYd" user "Package Geometry/Place Bound Top")
		(29 "B.CrtYd" user "Package Geometry/Place Bound Bottom")
		(35 "F.Fab" user "Ref Des/Assembly Top")
		(33 "B.Fab" user "Ref Des/Assembly Bottom")
		(45 "User.4" user "COMPVAL_TYPE_BOTTOM")
	)
	(footprint ""
		(layer "F.Cu")
		(at 22.987 44.069 90)
		(property "Reference" "R312"
			(at -1.80467 -2.413 0)
			(unlocked yes)
			(layer "F.SilkS")
			(effects
				(font
					(size 0.7874 0.5842)
					(thickness 0.127)
				)
				(justify left)
			)
		)
		(property "Value" "1.0K"
			(at -0.148158 1.3462 180)
			(unlocked yes)
			(layer "F.Fab")
			(hide yes)
			(effects
				(font
					(size 1.27 0.9652)
					(thickness 0.000001)
				)
				(justify left)
			)
		)
		(property "Device Type" "REST0025"
			(at -0.148158 1.3462 180)
			(unlocked yes)
			(layer "F.Fab")
			(hide yes)
			(effects
				(font
					(size 1.27 0.9652)
					(thickness 0.000001)
				)
				(justify left)
			)
		)
		(duplicate_pad_numbers_are_jumpers no)
		(fp_poly
			(pts
				(xy 0.635 1.0668) (xy 0.635 -1.0668) (xy -0.635 -1.0668) (xy -0.635 1.0668)
			)
			(stroke
				(width 0)
				(type default)
			)
			(fill no)
			(layer "F.CrtYd")
		)
		(fp_line
			(start 0.254 -0.508)
			(end 0.254 0.508)
			(stroke
				(width 0.0254)
				(type default)
			)
			(layer "F.Fab")
		)
		(fp_line
			(start -0.254 -0.508)
			(end 0.254 -0.508)
			(stroke
				(width 0.0254)
				(type default)
			)
			(layer "F.Fab")
		)
		(fp_line
			(start 0.254 0.508)
			(end -0.254 0.508)
			(stroke
				(width 0.0254)
				(type default)
			)
			(layer "F.Fab")
		)
		(fp_line
			(start -0.254 0.508)
			(end -0.254 -0.508)
			(stroke
				(width 0.0254)
				(type default)
			)
			(layer "F.Fab")
		)
		(pad "1" smd rect
			(at 0 -0.4191 90)
			(size 0.508 0.5334)
			(layers "F.Cu" "F.Mask" "F.Paste")
			(net "EXT_12.0V")
		)
		(pad "2" smd rect
			(at 0 0.4191 90)
			(size 0.508 0.5334)
			(layers "F.Cu" "F.Mask" "F.Paste")
			(net "10N2407")
		)
		(zone
			(layer "F.Cu")
			(hatch none 0.5)
			(connect_pads
				(clearance 0)
			)
			(min_thickness 0.25)
			(keepout
				(tracks not_allowed)
				(vias allowed)
				(pads allowed)
				(copperpour not_allowed)
				(footprints allowed)
			)
			(placement
				(enabled no)
				(sheetname "")
			)
			(fill
				(thermal_gap 0.5)
				(thermal_bridge_width 0.5)
				(island_removal_mode 0)
			)
			(polygon
				(pts
					(xy 22.9616 44.0436) (xy 23.0124 44.0436) (xy 23.0124 44.0944) (xy 22.9616 44.0944)
				)
			)
		)
	)
	(footprint ""
		(layer "F.Cu")
		(at 36.322 32.639 180)
		(property "Reference" "R79"
			(at 0 0 180)
			(layer "F.SilkS")
			(hide yes)
			(effects
				(font
					(size 1.27 1.27)
				)
			)
		)
		(property "Value" "4.75K"
			(at -0.148158 1.3462 270)
			(unlocked yes)
			(layer "F.Fab")
			(hide yes)
			(effects
				(font
					(size 1.27 0.9652)
					(thickness 0.000001)
				)
				(justify left)
			)
		)
		(property "Device Type" "REST4024"
			(at -0.148158 1.3462 270)
			(unlocked yes)
			(layer "F.Fab")
			(hide yes)
			(effects
				(font
					(size 1.27 0.9652)
					(thickness 0.000001)
				)
				(justify left)
			)
		)
		(duplicate_pad_numbers_are_jumpers no)
		(fp_poly
			(pts
				(xy 0.635 1.0668) (xy 0.635 -1.0668) (xy -0.635 -1.0668) (xy -0.635 1.0668)
			)
			(stroke
				(width 0)
				(type default)
			)
			(fill no)
			(layer "F.CrtYd")
		)
		(fp_line
			(start 0.254 0.508)
			(end -0.254 0.508)
			(stroke
				(width 0.0254)
				(type default)
			)
			(layer "F.Fab")
		)
		(fp_line
			(start 0.254 -0.508)
			(end 0.254 0.508)
			(stroke
				(width 0.0254)
				(type default)
			)
			(layer "F.Fab")
		)
		(fp_line
			(start -0.254 0.508)
			(end -0.254 -0.508)
			(stroke
				(width 0.0254)
				(type default)
			)
			(layer "F.Fab")
		)
		(fp_line
			(start -0.254 -0.508)
			(end 0.254 -0.508)
			(stroke
				(width 0.0254)
				(type default)
			)
			(layer "F.Fab")
		)
		(pad "1" smd rect
			(at 0 -0.4191 180)
			(size 0.508 0.5334)
			(layers "F.Cu" "F.Mask" "F.Paste")
			(net "_NFP_CORE_VID7")
		)
		(pad "2" smd rect
			(at 0 0.4191 180)
			(size 0.508 0.5334)
			(layers "F.Cu" "F.Mask" "F.Paste")
			(net "VDD_1.2V")
		)
		(zone
			(layer "F.Cu")
			(hatch none 0.5)
			(connect_pads
				(clearance 0)
			)
			(min_thickness 0.25)
			(keepout
				(tracks not_allowed)
				(vias allowed)
				(pads allowed)
				(copperpour not_allowed)
				(footprints allowed)
			)
			(placement
				(enabled no)
				(sheetname "")
			)
			(fill
				(thermal_gap 0.5)
				(thermal_bridge_width 0.5)
				(island_removal_mode 0)
			)
			(polygon
				(pts
					(xy 36.2966 32.6644) (xy 36.2966 32.6136) (xy 36.3474 32.6136) (xy 36.3474 32.6644)
				)
			)
		)
	)
	(footprint ""
		(layer "F.Cu")
		(at 9.7155 34.417 180)
		(property "Reference" "C20"
			(at 0.86233 0.762 90)
			(unlocked yes)
			(layer "F.SilkS")
			(effects
				(font
					(size 0.7874 0.5842)
					(thickness 0.127)
				)
				(justify left)
			)
		)
		(property "Value" "22UF"
			(at -0.148158 1.7526 270)
			(unlocked yes)
			(layer "F.Fab")
			(hide yes)
			(effects
				(font
					(size 1.27 0.9652)
					(thickness 0.000001)
				)
				(justify left)
			)
		)
		(property "Device Type" "CAPC0063"
			(at -0.148158 1.7526 270)
			(unlocked yes)
			(layer "F.Fab")
			(hide yes)
			(effects
				(font
					(size 1.27 0.9652)
					(thickness 0.000001)
				)
				(justify left)
			)
		)
		(duplicate_pad_numbers_are_jumpers no)
		(fp_circle
			(center 0 0)
			(end -0.127 0)
			(stroke
				(width 0.2032)
				(type default)
			)
			(fill no)
			(layer "F.SilkS")
		)
		(fp_poly
			(pts
				(xy 0.7874 -1.6637) (xy -0.7874 -1.6637) (xy -0.7874 1.6637) (xy 0.7874 1.6637)
			)
			(stroke
				(width 0)
				(type default)
			)
			(fill no)
			(layer "F.CrtYd")
		)
		(fp_line
			(start 0.4064 0.8128)
			(end -0.4064 0.8128)
			(stroke
				(width 0.0254)
				(type default)
			)
			(layer "F.Fab")
		)
		(fp_line
			(start 0.4064 -0.7874)
			(end 0.4064 0.8128)
			(stroke
				(width 0.0254)
				(type default)
			)
			(layer "F.Fab")
		)
		(fp_line
			(start -0.4064 0.8128)
			(end -0.4064 -0.7874)
			(stroke
				(width 0.0254)
				(type default)
			)
			(layer "F.Fab")
		)
		(fp_line
			(start -0.4064 -0.7874)
			(end 0.4064 -0.7874)
			(stroke
				(width 0.0254)
				(type default)
			)
			(layer "F.Fab")
		)
		(pad "1" smd rect
			(at 0 -0.8001 180)
			(size 0.8636 0.9652)
			(layers "F.Cu" "F.Mask" "F.Paste")
			(net "VDD_1.2V")
		)
		(pad "2" smd rect
			(at 0 0.8001 180)
			(size 0.8636 0.9652)
			(layers "F.Cu" "F.Mask" "F.Paste")
			(net "GND")
		)
		(zone
			(layer "F.Cu")
			(hatch none 0.5)
			(connect_pads
				(clearance 0)
			)
			(min_thickness 0.25)
			(keepout
				(tracks not_allowed)
				(vias allowed)
				(pads allowed)
				(copperpour not_allowed)
				(footprints allowed)
			)
			(placement
				(enabled no)
				(sheetname "")
			)
			(fill
				(thermal_gap 0.5)
				(thermal_bridge_width 0.5)
				(island_removal_mode 0)
			)
			(polygon
				(pts
					(xy 9.779 34.671) (xy 9.652 34.671) (xy 9.652 34.163) (xy 9.779 34.163)
				)
			)
		)
	)
	(footprint ""
		(layer "F.Cu")
		(at 17.272 28.8925 -90)
		(property "Reference" "TP56"
			(at -0.8255 1.11633 90)
			(unlocked yes)
			(layer "F.SilkS")
			(effects
				(font
					(size 0.7874 0.5842)
					(thickness 0.127)
				)
				(justify left)
			)
		)
		(property "Value" "*"
			(at -0.4826 -0.14732 270)
			(unlocked yes)
			(layer "F.Fab")
			(hide yes)
			(effects
				(font
					(size 1.27 0.9652)
					(thickness 0.000001)
				)
				(justify left)
			)
		)
		(property "Device Type" "TP_SMALL"
			(at -0.4826 -0.14732 270)
			(unlocked yes)
			(layer "F.Fab")
			(hide yes)
			(effects
				(font
					(size 1.27 0.9652)
					(thickness 0.000001)
				)
				(justify left)
			)
		)
		(duplicate_pad_numbers_are_jumpers no)
		(fp_line
			(start -0.8636 0.8636)
			(end 0.8636 0.8636)
			(stroke
				(width 0.1524)
				(type default)
			)
			(layer "F.SilkS")
		)
		(fp_line
			(start 0.8636 0.8636)
			(end 0.8636 -0.8636)
			(stroke
				(width 0.1524)
				(type default)
			)
			(layer "F.SilkS")
		)
		(fp_line
			(start -0.8636 -0.8636)
			(end -0.8636 0.8636)
			(stroke
				(width 0.1524)
				(type default)
			)
			(layer "F.SilkS")
		)
		(fp_line
			(start 0.8636 -0.8636)
			(end -0.8636 -0.8636)
			(stroke
				(width 0.1524)
				(type default)
			)
			(layer "F.SilkS")
		)
		(fp_poly
			(pts
				(xy -0.635 -0.635) (xy -0.635 0.635) (xy 0.635 0.635) (xy 0.635 -0.635)
			)
			(stroke
				(width 0)
				(type default)
			)
			(fill no)
			(layer "F.CrtYd")
		)
		(pad "1" smd rect
			(at 0 0 270)
			(size 1.27 1.27)
			(layers "F.Cu" "F.Mask" "F.Paste")
			(net "VDD_3.3V")
		)
	)
	(footprint ""
		(layer "F.Cu")
		(at 21.5265 6.35 -90)
		(property "Reference" "R381"
			(at 0 0 270)
			(layer "F.SilkS")
			(hide yes)
			(effects
				(font
					(size 1.27 1.27)
				)
			)
		)
		(property "Value" "0"
			(at -0.148158 1.3462 0)
			(unlocked yes)
			(layer "F.Fab")
			(hide yes)
			(effects
				(font
					(size 1.27 0.9652)
					(thickness 0.000001)
				)
				(justify left)
			)
		)
		(property "Device Type" "REST1111"
			(at -0.148158 1.3462 0)
			(unlocked yes)
			(layer "F.Fab")
			(hide yes)
			(effects
				(font
					(size 1.27 0.9652)
					(thickness 0.000001)
				)
				(justify left)
			)
		)
		(duplicate_pad_numbers_are_jumpers no)
		(fp_poly
			(pts
				(xy 0.635 1.0668) (xy 0.635 -1.0668) (xy -0.635 -1.0668) (xy -0.635 1.0668)
			)
			(stroke
				(width 0)
				(type default)
			)
			(fill no)
			(layer "F.CrtYd")
		)
		(fp_line
			(start -0.254 0.508)
			(end -0.254 -0.508)
			(stroke
				(width 0.0254)
				(type default)
			)
			(layer "F.Fab")
		)
		(fp_line
			(start 0.254 0.508)
			(end -0.254 0.508)
			(stroke
				(width 0.0254)
				(type default)
			)
			(layer "F.Fab")
		)
		(fp_line
			(start -0.254 -0.508)
			(end 0.254 -0.508)
			(stroke
				(width 0.0254)
				(type default)
			)
			(layer "F.Fab")
		)
		(fp_line
			(start 0.254 -0.508)
			(end 0.254 0.508)
			(stroke
				(width 0.0254)
				(type default)
			)
			(layer "F.Fab")
		)
		(pad "1" smd rect
			(at 0 -0.4191 270)
			(size 0.508 0.5334)
			(layers "F.Cu" "F.Mask" "F.Paste")
			(net "NFP_SMBUS_ALERT_L")
		)
		(pad "2" smd rect
			(at 0 0.4191 270)
			(size 0.508 0.5334)
			(layers "F.Cu" "F.Mask" "F.Paste")
			(net "MUX_NFP_SMBUS_ALERT_L")
		)
		(zone
			(layer "F.Cu")
			(hatch none 0.5)
			(connect_pads
				(clearance 0)
			)
			(min_thickness 0.25)
			(keepout
				(tracks not_allowed)
				(vias allowed)
				(pads allowed)
				(copperpour not_allowed)
				(footprints allowed)
			)
			(placement
				(enabled no)
				(sheetname "")
			)
			(fill
				(thermal_gap 0.5)
				(thermal_bridge_width 0.5)
				(island_removal_mode 0)
			)
			(polygon
				(pts
					(xy 21.5519 6.3754) (xy 21.5011 6.3754) (xy 21.5011 6.3246) (xy 21.5519 6.3246)
				)
			)
		)
	)
	(footprint ""
		(layer "F.Cu")
		(at 36.322 37.211 90)
		(property "Reference" "R181"
			(at 0 0 90)
			(layer "F.SilkS")
			(hide yes)
			(effects
				(font
					(size 1.27 1.27)
				)
			)
		)
		(property "Value" "0"
			(at -0.148158 1.3462 180)
			(unlocked yes)
			(layer "F.Fab")
			(hide yes)
			(effects
				(font
					(size 1.27 0.9652)
					(thickness 0.000001)
				)
				(justify left)
			)
		)
		(property "Device Type" "REST1111"
			(at -0.148158 1.3462 180)
			(unlocked yes)
			(layer "F.Fab")
			(hide yes)
			(effects
				(font
					(size 1.27 0.9652)
					(thickness 0.000001)
				)
				(justify left)
			)
		)
		(duplicate_pad_numbers_are_jumpers no)
		(fp_poly
			(pts
				(xy 0.635 1.0668) (xy 0.635 -1.0668) (xy -0.635 -1.0668) (xy -0.635 1.0668)
			)
			(stroke
				(width 0)
				(type default)
			)
			(fill no)
			(layer "F.CrtYd")
		)
		(fp_line
			(start 0.254 -0.508)
			(end 0.254 0.508)
			(stroke
				(width 0.0254)
				(type default)
			)
			(layer "F.Fab")
		)
		(fp_line
			(start -0.254 -0.508)
			(end 0.254 -0.508)
			(stroke
				(width 0.0254)
				(type default)
			)
			(layer "F.Fab")
		)
		(fp_line
			(start 0.254 0.508)
			(end -0.254 0.508)
			(stroke
				(width 0.0254)
				(type default)
			)
			(layer "F.Fab")
		)
		(fp_line
			(start -0.254 0.508)
			(end -0.254 -0.508)
			(stroke
				(width 0.0254)
				(type default)
			)
			(layer "F.Fab")
		)
		(pad "1" smd rect
			(at 0 -0.4191 90)
			(size 0.508 0.5334)
			(layers "F.Cu" "F.Mask" "F.Paste")
			(net "10N2403")
		)
		(pad "2" smd rect
			(at 0 0.4191 90)
			(size 0.508 0.5334)
			(layers "F.Cu" "F.Mask" "F.Paste")
			(net "VDD_5.0V")
		)
		(zone
			(layer "F.Cu")
			(hatch none 0.5)
			(connect_pads
				(clearance 0)
			)
			(min_thickness 0.25)
			(keepout
				(tracks not_allowed)
				(vias allowed)
				(pads allowed)
				(copperpour not_allowed)
				(footprints allowed)
			)
			(placement
				(enabled no)
				(sheetname "")
			)
			(fill
				(thermal_gap 0.5)
				(thermal_bridge_width 0.5)
				(island_removal_mode 0)
			)
			(polygon
				(pts
					(xy 36.2966 37.1856) (xy 36.3474 37.1856) (xy 36.3474 37.2364) (xy 36.2966 37.2364)
				)
			)
		)
	)
	(footprint ""
		(layer "F.Cu")
		(at 22.86 11.176 90)
		(property "Reference" "U8"
			(at 1.75133 -4.318 0)
			(unlocked yes)
			(layer "F.SilkS")
			(effects
				(font
					(size 0.7874 0.5842)
					(thickness 0.127)
				)
				(justify left)
			)
		)
		(property "Value" "*"
			(at -2.0066 1.756842 90)
			(unlocked yes)
			(layer "F.Fab")
			(hide yes)
			(effects
				(font
					(size 1.27 0.9652)
					(thickness 0.000001)
				)
				(justify left)
			)
		)
		(property "Device Type" "PROG0053"
			(at -2.0066 1.756842 90)
			(unlocked yes)
			(layer "F.Fab")
			(hide yes)
			(effects
				(font
					(size 1.27 0.9652)
					(thickness 0.000001)
				)
				(justify left)
			)
		)
		(duplicate_pad_numbers_are_jumpers no)
		(fp_line
			(start 2.286 -2.794)
			(end 2.286 -2.54)
			(stroke
				(width 0.2032)
				(type default)
			)
			(layer "F.SilkS")
		)
		(fp_line
			(start 0.252324 -2.794)
			(end 2.286 -2.794)
			(stroke
				(width 0.2032)
				(type default)
			)
			(layer "F.SilkS")
		)
		(fp_line
			(start -0.762 -2.794)
			(end -0.762 -1.905)
			(stroke
				(width 0.2032)
				(type default)
			)
			(layer "F.SilkS")
		)
		(fp_line
			(start -2.286 -2.794)
			(end 2.286 -2.794)
			(stroke
				(width 0.2032)
				(type default)
			)
			(layer "F.SilkS")
		)
		(fp_line
			(start -2.286 -2.794)
			(end -1.6256 -2.794)
			(stroke
				(width 0.2032)
				(type default)
			)
			(layer "F.SilkS")
		)
		(fp_line
			(start -2.286 -2.54)
			(end -2.286 -2.794)
			(stroke
				(width 0.2032)
				(type default)
			)
			(layer "F.SilkS")
		)
		(fp_line
			(start 0.762 -1.905)
			(end 0.762 -2.794)
			(stroke
				(width 0.2032)
				(type default)
			)
			(layer "F.SilkS")
		)
		(fp_line
			(start 0.762 -1.905)
			(end 0.762 -2.794)
			(stroke
				(width 0.2032)
				(type default)
			)
			(layer "F.SilkS")
		)
		(fp_line
			(start -0.762 -1.905)
			(end 0.762 -1.905)
			(stroke
				(width 0.2032)
				(type default)
			)
			(layer "F.SilkS")
		)
		(fp_line
			(start -2.286 2.54)
			(end -2.286 2.794)
			(stroke
				(width 0.2032)
				(type default)
			)
			(layer "F.SilkS")
		)
		(fp_line
			(start 2.286 2.794)
			(end 2.286 2.54)
			(stroke
				(width 0.2032)
				(type default)
			)
			(layer "F.SilkS")
		)
		(fp_line
			(start -1.054786 2.794)
			(end 1.6256 2.794)
			(stroke
				(width 0.2032)
				(type default)
			)
			(layer "F.SilkS")
		)
		(fp_line
			(start -2.286 2.794)
			(end 2.286 2.794)
			(stroke
				(width 0.2032)
				(type default)
			)
			(layer "F.SilkS")
		)
		(fp_arc
			(start -2.794 -3.048)
			(mid -2.614395 -2.973605)
			(end -2.54 -2.794)
			(stroke
				(width 0.2032)
				(type default)
			)
			(layer "F.SilkS")
		)
		(fp_arc
			(start -2.54 -2.794)
			(mid -2.572074 -2.67045)
			(end -2.660193 -2.5781)
			(stroke
				(width 0.2032)
				(type default)
			)
			(layer "F.SilkS")
		)
		(fp_arc
			(start -3.048 -2.794)
			(mid -2.973605 -2.973605)
			(end -2.794 -3.048)
			(stroke
				(width 0.2032)
				(type default)
			)
			(layer "F.SilkS")
		)
		(fp_arc
			(start -2.927807 -2.5781)
			(mid -3.015928 -2.670449)
			(end -3.048 -2.794)
			(stroke
				(width 0.2032)
				(type default)
			)
			(layer "F.SilkS")
		)
		(fp_circle
			(center -2.794 -2.794)
			(end -2.794 -2.54)
			(stroke
				(width 0.2032)
				(type default)
			)
			(fill no)
			(layer "F.SilkS")
		)
		(fp_poly
			(pts
				(xy 2.54 3.048) (xy 2.54 2.921) (xy 4.191 2.921) (xy 4.191 -2.921) (xy 2.54 -2.921) (xy 2.54 -3.048)
				(xy -2.54 -3.048) (xy -2.54 -2.921) (xy -4.191 -2.921) (xy -4.191 2.921) (xy -2.54 2.921) (xy -2.54 3.048)
			)
			(stroke
				(width 0)
				(type default)
			)
			(fill no)
			(layer "F.CrtYd")
		)
		(fp_line
			(start 2.0066 -2.5019)
			(end -2.0066 -2.5019)
			(stroke
				(width 0.2032)
				(type default)
			)
			(layer "F.Fab")
		)
		(fp_line
			(start -2.0066 -2.5019)
			(end -2.0066 2.5019)
			(stroke
				(width 0.2032)
				(type default)
			)
			(layer "F.Fab")
		)
		(fp_line
			(start -0.635 -2.4892)
			(end -0.635 -1.7272)
			(stroke
				(width 0.2032)
				(type default)
			)
			(layer "F.Fab")
		)
		(fp_line
			(start 0.635 -1.7272)
			(end 0.635 -2.4892)
			(stroke
				(width 0.2032)
				(type default)
			)
			(layer "F.Fab")
		)
		(fp_line
			(start -0.635 -1.7272)
			(end 0.635 -1.7272)
			(stroke
				(width 0.2032)
				(type default)
			)
			(layer "F.Fab")
		)
		(fp_line
			(start 2.0066 2.5019)
			(end 2.0066 -2.5019)
			(stroke
				(width 0.2032)
				(type default)
			)
			(layer "F.Fab")
		)
		(fp_line
			(start -2.0066 2.5019)
			(end 2.0066 2.5019)
			(stroke
				(width 0.2032)
				(type default)
			)
			(layer "F.Fab")
		)
		(fp_circle
			(center -1.524 -1.905)
			(end -1.524 -1.621028)
			(stroke
				(width 0.2032)
				(type default)
			)
			(fill no)
			(layer "F.Fab")
		)
		(pad "1" smd rect
			(at -2.667 -1.905 90)
			(size 2.032 0.635)
			(layers "F.Cu" "F.Mask" "F.Paste")
			(net "NFP_CFG_SPI_FLASH_SEL")
		)
		(pad "2" smd rect
			(at -2.667 -0.635 90)
			(size 2.032 0.635)
			(layers "F.Cu" "F.Mask" "F.Paste")
			(net "NFP_CFG_SPI_FLASH_MISO")
		)
		(pad "3" smd rect
			(at -2.667 0.635 90)
			(size 2.032 0.635)
			(layers "F.Cu" "F.Mask" "F.Paste")
			(net "NFP_CFG_SPI_FLASH_WP_L")
		)
		(pad "4" smd rect
			(at -2.667 1.905 90)
			(size 2.032 0.635)
			(layers "F.Cu" "F.Mask" "F.Paste")
			(net "GND")
		)
		(pad "5" smd rect
			(at 2.667 1.905 90)
			(size 2.032 0.635)
			(layers "F.Cu" "F.Mask" "F.Paste")
			(net "NFP_CFG_SPI_FLASH_MOSI")
		)
		(pad "6" smd rect
			(at 2.667 0.635 90)
			(size 2.032 0.635)
			(layers "F.Cu" "F.Mask" "F.Paste")
			(net "NFP_CFG_SPI_FLASH_SCK")
		)
		(pad "7" smd rect
			(at 2.667 -0.635 90)
			(size 2.032 0.635)
			(layers "F.Cu" "F.Mask" "F.Paste")
			(net "NFP_CFG_SPI_FLASH_HOLD_L")
		)
		(pad "8" smd rect
			(at 2.667 -1.905 90)
			(size 2.032 0.635)
			(layers "F.Cu" "F.Mask" "F.Paste")
			(net "VDD_3.3V")
		)
	)
)
